(kicad_pcb
	(version 20241229)
	(generator "pcbnew")
	(generator_version "9.0")
	(general
		(thickness 1.552)
		(legacy_teardrops no)
	)
	(paper "A4")
	(title_block
		(date "2023-07-25")
		(rev "1.1.4")
		(comment 9 "footprints 206-209 of 379")
	)
	(layers
		(0 "F.Cu" signal)
		(4 "In1.Cu" signal)
		(6 "In2.Cu" signal)
		(8 "In3.Cu" signal)
		(10 "In4.Cu" signal)
		(12 "In5.Cu" signal)
		(14 "In6.Cu" signal)
		(2 "B.Cu" signal)
		(9 "F.Adhes" user "F.Adhesive")
		(11 "B.Adhes" user "B.Adhesive")
		(13 "F.Paste" user)
		(15 "B.Paste" user)
		(5 "F.SilkS" user "F.Silkscreen")
		(7 "B.SilkS" user "B.Silkscreen")
		(1 "F.Mask" user)
		(3 "B.Mask" user)
		(17 "Dwgs.User" user "User.Drawings")
		(19 "Cmts.User" user "User.Comments")
		(21 "Eco1.User" user "User.Eco1")
		(23 "Eco2.User" user "User.Eco2")
		(25 "Edge.Cuts" user)
		(27 "Margin" user)
		(31 "F.CrtYd" user "F.Courtyard")
		(29 "B.CrtYd" user "B.Courtyard")
		(35 "F.Fab" user)
		(33 "B.Fab" user)
	)
	(footprint "antmicro-footprints:R_0603_1608Metric"
		(layer "F.Cu")
		(at 105.58 70.55 90)
		(descr "Resistor SMD 0603")
		(tags "resistor SMD 0603")
		(property "Reference" "R100"
			(at 1.41 0.45 90)
			(layer "F.SilkS")
			(effects
				(font
					(size 0.65 0.65)
					(thickness 0.15)
				)
				(justify left bottom)
			)
		)
		(property "Value" "R_200R_0603"
			(at 0 1.6 90)
			(layer "F.Fab")
			(hide yes)
			(effects
				(font
					(size 0.7 0.7)
					(thickness 0.15)
				)
				(justify left bottom)
			)
		)
		(property "Datasheet" "https://www.bourns.com/docs/product-datasheets/cr.pdf"
			(at 0 0 90)
			(layer "F.Fab")
			(hide yes)
			(effects
				(font
					(size 1.27 1.27)
					(thickness 0.15)
				)
			)
		)
		(property "Description" "SMD Chip Resistor, 200 ohm, ± 1%, 100 mW, 0603 [1608 Metric], Thick Film, General Purpose"
			(at 0 0 90)
			(layer "F.Fab")
			(hide yes)
			(effects
				(font
					(size 1.27 1.27)
					(thickness 0.15)
				)
			)
		)
		(property "Author" "Antmicro"
			(at 176.13 -35.03 0)
			(layer "F.Fab")
			(hide yes)
			(effects
				(font
					(size 1 1)
					(thickness 0.15)
				)
			)
		)
		(property "License" "Apache-2.0"
			(at 176.13 -35.03 0)
			(layer "F.Fab")
			(hide yes)
			(effects
				(font
					(size 1 1)
					(thickness 0.15)
				)
			)
		)
		(property "MPN" "CR0603-FX-2000ELF"
			(at 176.13 -35.03 0)
			(layer "F.Fab")
			(hide yes)
			(effects
				(font
					(size 1 1)
					(thickness 0.15)
				)
			)
		)
		(property "Manufacturer" "Bourns"
			(at 176.13 -35.03 0)
			(layer "F.Fab")
			(hide yes)
			(effects
				(font
					(size 1 1)
					(thickness 0.15)
				)
			)
		)
		(property "Tolerance" "1%"
			(at 176.13 -35.03 0)
			(layer "F.Fab")
			(hide yes)
			(effects
				(font
					(size 1 1)
					(thickness 0.15)
				)
			)
		)
		(property "Val" "200R"
			(at 176.13 -35.03 0)
			(layer "F.Fab")
			(hide yes)
			(effects
				(font
					(size 1 1)
					(thickness 0.15)
				)
			)
		)
		(sheetname "/SDI/")
		(sheetfile "sdi.kicad_sch")
		(attr smd)
		(fp_line
			(start -0.15 -0.4)
			(end 0.15 -0.4)
			(stroke
				(width 0.15)
				(type solid)
			)
			(layer "F.SilkS")
		)
		(fp_line
			(start -0.15 0.4)
			(end 0.15 0.4)
			(stroke
				(width 0.15)
				(type solid)
			)
			(layer "F.SilkS")
		)
		(fp_rect
			(start -1.25 -0.65)
			(end 1.25 0.65)
			(stroke
				(width 0.05)
				(type solid)
			)
			(fill no)
			(layer "F.CrtYd")
		)
		(fp_rect
			(start -0.8 -0.4)
			(end 0.8 0.4)
			(stroke
				(width 0.15)
				(type solid)
			)
			(fill no)
			(layer "F.Fab")
		)
		(fp_text user "License: Apache-2.0"
			(at -1.25 5.9 90)
			(layer "F.Fab")
			(effects
				(font
					(size 0.7 0.7)
					(thickness 0.15)
				)
				(justify left bottom)
			)
		)
		(fp_text user "${REFERENCE}"
			(at -1.25 3.898 90)
			(layer "F.Fab")
			(effects
				(font
					(size 0.7 0.7)
					(thickness 0.15)
				)
				(justify left bottom)
			)
		)
		(fp_text user "Author: Antmicro"
			(at -1.25 4.9 90)
			(layer "F.Fab")
			(effects
				(font
					(size 0.7 0.7)
					(thickness 0.15)
				)
				(justify left bottom)
			)
		)
		(pad "1" smd roundrect
			(at -0.7 0 90)
			(size 0.8 1)
			(layers "F.Cu" "F.Mask" "F.Paste")
			(roundrect_rratio 0.2)
			(net 246 "Net-(D7-A)")
			(pintype "passive")
		)
		(pad "2" smd roundrect
			(at 0.7 0 90)
			(size 0.8 1)
			(layers "F.Cu" "F.Mask" "F.Paste")
			(roundrect_rratio 0.2)
			(net 183 "/SDI/SDI_STAT5")
			(pintype "passive")
		)
	)
	(footprint "antmicro-footprints:R_0603_1608Metric"
		(layer "F.Cu")
		(at 138.79 112.9 90)
		(descr "Resistor SMD 0603")
		(tags "resistor SMD 0603")
		(property "Reference" "R37"
			(at -1.64 -0.96 90)
			(layer "F.SilkS")
			(effects
				(font
					(size 0.65 0.65)
					(thickness 0.15)
				)
				(justify left bottom)
			)
		)
		(property "Value" "R_0R_0603"
			(at 0 1.6 90)
			(layer "F.Fab")
			(hide yes)
			(effects
				(font
					(size 0.7 0.7)
					(thickness 0.15)
				)
				(justify left bottom)
			)
		)
		(property "Datasheet" "https://www.bourns.com/docs/product-datasheets/cr.pdf?sfvrsn=574d41f6_14"
			(at 0 0 90)
			(layer "F.Fab")
			(hide yes)
			(effects
				(font
					(size 1.27 1.27)
					(thickness 0.15)
				)
			)
		)
		(property "Description" "Zero Ohm Resistor, Jumper, 0603 [1608 Metric], Thick Film, 100 mW, 1 A, Surface Mount Device, CR"
			(at 0 0 90)
			(layer "F.Fab")
			(hide yes)
			(effects
				(font
					(size 1.27 1.27)
					(thickness 0.15)
				)
			)
		)
		(property "Author" "Antmicro"
			(at 251.69 -25.89 0)
			(layer "F.Fab")
			(hide yes)
			(effects
				(font
					(size 1 1)
					(thickness 0.15)
				)
			)
		)
		(property "Current" "1A"
			(at 251.69 -25.89 0)
			(layer "F.Fab")
			(hide yes)
			(effects
				(font
					(size 1 1)
					(thickness 0.15)
				)
			)
		)
		(property "License" "Apache-2.0"
			(at 251.69 -25.89 0)
			(layer "F.Fab")
			(hide yes)
			(effects
				(font
					(size 1 1)
					(thickness 0.15)
				)
			)
		)
		(property "MPN" "CR0603-J/-000ELF"
			(at 251.69 -25.89 0)
			(layer "F.Fab")
			(hide yes)
			(effects
				(font
					(size 1 1)
					(thickness 0.15)
				)
			)
		)
		(property "Manufacturer" "Bourns"
			(at 251.69 -25.89 0)
			(layer "F.Fab")
			(hide yes)
			(effects
				(font
					(size 1 1)
					(thickness 0.15)
				)
			)
		)
		(property "Tolerance" "~"
			(at 251.69 -25.89 0)
			(layer "F.Fab")
			(hide yes)
			(effects
				(font
					(size 1 1)
					(thickness 0.15)
				)
			)
		)
		(property "Val" "0R"
			(at 251.69 -25.89 0)
			(layer "F.Fab")
			(hide yes)
			(effects
				(font
					(size 1 1)
					(thickness 0.15)
				)
			)
		)
		(sheetname "/Power Supply/")
		(sheetfile "supply.kicad_sch")
		(attr smd)
		(fp_line
			(start -0.15 -0.4)
			(end 0.15 -0.4)
			(stroke
				(width 0.15)
				(type solid)
			)
			(layer "F.SilkS")
		)
		(fp_line
			(start -0.15 0.4)
			(end 0.15 0.4)
			(stroke
				(width 0.15)
				(type solid)
			)
			(layer "F.SilkS")
		)
		(fp_rect
			(start -1.25 -0.65)
			(end 1.25 0.65)
			(stroke
				(width 0.05)
				(type solid)
			)
			(fill no)
			(layer "F.CrtYd")
		)
		(fp_rect
			(start -0.8 -0.4)
			(end 0.8 0.4)
			(stroke
				(width 0.15)
				(type solid)
			)
			(fill no)
			(layer "F.Fab")
		)
		(fp_text user "License: Apache-2.0"
			(at -1.25 5.9 90)
			(layer "F.Fab")
			(effects
				(font
					(size 0.7 0.7)
					(thickness 0.15)
				)
				(justify left bottom)
			)
		)
		(fp_text user "Author: Antmicro"
			(at -1.25 4.9 90)
			(layer "F.Fab")
			(effects
				(font
					(size 0.7 0.7)
					(thickness 0.15)
				)
				(justify left bottom)
			)
		)
		(fp_text user "${REFERENCE}"
			(at -1.25 3.898 90)
			(layer "F.Fab")
			(effects
				(font
					(size 0.7 0.7)
					(thickness 0.15)
				)
				(justify left bottom)
			)
		)
		(pad "1" smd roundrect
			(at -0.7 0 90)
			(size 0.8 1)
			(layers "F.Cu" "F.Mask" "F.Paste")
			(roundrect_rratio 0.2)
			(net 284 "Net-(U10-V_{OUT})")
			(pintype "passive")
		)
		(pad "2" smd roundrect
			(at 0.7 0 90)
			(size 0.8 1)
			(layers "F.Cu" "F.Mask" "F.Paste")
			(roundrect_rratio 0.2)
			(net 50 "+1V8")
			(pintype "passive")
		)
	)
	(footprint "antmicro-footprints:Conn_BNC_031-70526-21"
		(layer "F.Cu")
		(at 68.45 74.85 -90)
		(property "Reference" "J2"
			(at 6.69 -7.98 0)
			(unlocked yes)
			(layer "F.SilkS")
			(effects
				(font
					(size 0.65 0.65)
					(thickness 0.15)
				)
				(justify left bottom)
			)
		)
		(property "Value" "Conn_BNC_031-70526-21"
			(at 0 13.9 90)
			(layer "F.Fab")
			(hide yes)
			(effects
				(font
					(size 0.7 0.7)
					(thickness 0.15)
				)
				(justify right bottom)
			)
		)
		(property "Datasheet" "https://www.farnell.com/cad/2305565.pdf?_ga=2.190633003.1014497200.1574067480-156563690.1566371002&_gac=1.57062104.1572875319.Cj0KCQiAtf_tBRDtARIsAIbAKe0A1M5y_jdFCiNLNrHM5L2GjmDvn_4qnRvhHAD9jBdL9AmoMNThLCoaAjhJEALw_wcB"
			(at 0 0 270)
			(layer "F.Fab")
			(hide yes)
			(effects
				(font
					(size 1.27 1.27)
					(thickness 0.15)
				)
			)
		)
		(property "Description" "RF / Coaxial Connector, BNC Coaxial, Straight Bulkhead Jack, Board Edge / End Launch, 75 ohm"
			(at 0 0 270)
			(layer "F.Fab")
			(hide yes)
			(effects
				(font
					(size 1.27 1.27)
					(thickness 0.15)
				)
			)
		)
		(property "Author" "Antmicro"
			(at -6.4 143.3 0)
			(layer "F.Fab")
			(hide yes)
			(effects
				(font
					(size 1 1)
					(thickness 0.15)
				)
			)
		)
		(property "License" "Apache-2.0"
			(at -6.4 143.3 0)
			(layer "F.Fab")
			(hide yes)
			(effects
				(font
					(size 1 1)
					(thickness 0.15)
				)
			)
		)
		(property "MPN" "031-70526-21"
			(at -6.4 143.3 0)
			(layer "F.Fab")
			(hide yes)
			(effects
				(font
					(size 1 1)
					(thickness 0.15)
				)
			)
		)
		(property "Manufacturer" "Amphenol"
			(at -6.4 143.3 0)
			(layer "F.Fab")
			(hide yes)
			(effects
				(font
					(size 1 1)
					(thickness 0.15)
				)
			)
		)
		(property ki_fp_filters "*BNC* *SMA* *SMB* *SMC* *Cinch*")
		(sheetname "/SDI/")
		(sheetfile "sdi.kicad_sch")
		(attr smd)
		(fp_line
			(start 7.3 12.9)
			(end -7.4 12.9)
			(stroke
				(width 0.05)
				(type solid)
			)
			(layer "B.CrtYd")
		)
		(fp_line
			(start -8.2 -4.6)
			(end -7.4 -4.6)
			(stroke
				(width 0.05)
				(type solid)
			)
			(layer "B.CrtYd")
		)
		(fp_line
			(start -7.4 -4.6)
			(end -7.4 12.9)
			(stroke
				(width 0.05)
				(type solid)
			)
			(layer "B.CrtYd")
		)
		(fp_line
			(start 7.3 -4.6)
			(end 7.3 12.9)
			(stroke
				(width 0.05)
				(type solid)
			)
			(layer "B.CrtYd")
		)
		(fp_line
			(start 8.1 -4.6)
			(end 7.3 -4.6)
			(stroke
				(width 0.05)
				(type solid)
			)
			(layer "B.CrtYd")
		)
		(fp_line
			(start -8.2 -5.5)
			(end -8.2 -4.6)
			(stroke
				(width 0.05)
				(type solid)
			)
			(layer "B.CrtYd")
		)
		(fp_line
			(start -6.6 -5.5)
			(end -8.2 -5.5)
			(stroke
				(width 0.05)
				(type solid)
			)
			(layer "B.CrtYd")
		)
		(fp_line
			(start 6.5 -5.5)
			(end 8.1 -5.5)
			(stroke
				(width 0.05)
				(type solid)
			)
			(layer "B.CrtYd")
		)
		(fp_line
			(start 8.1 -5.5)
			(end 8.1 -4.6)
			(stroke
				(width 0.05)
				(type solid)
			)
			(layer "B.CrtYd")
		)
		(fp_line
			(start -6.6 -6.6)
			(end -6.6 -5.5)
			(stroke
				(width 0.05)
				(type solid)
			)
			(layer "B.CrtYd")
		)
		(fp_line
			(start -5.7 -6.6)
			(end -6.6 -6.6)
			(stroke
				(width 0.05)
				(type solid)
			)
			(layer "B.CrtYd")
		)
		(fp_line
			(start 5.6 -6.6)
			(end 6.5 -6.6)
			(stroke
				(width 0.05)
				(type solid)
			)
			(layer "B.CrtYd")
		)
		(fp_line
			(start 6.5 -6.6)
			(end 6.5 -5.5)
			(stroke
				(width 0.05)
				(type solid)
			)
			(layer "B.CrtYd")
		)
		(fp_line
			(start 4.1 -12.9)
			(end -4.2 -12.9)
			(stroke
				(width 0.05)
				(type solid)
			)
			(layer "B.CrtYd")
		)
		(fp_line
			(start -5.7 -13.6)
			(end -5.7 -6.6)
			(stroke
				(width 0.05)
				(type solid)
			)
			(layer "B.CrtYd")
		)
		(fp_line
			(start -4.2 -13.6)
			(end -4.2 -12.9)
			(stroke
				(width 0.05)
				(type solid)
			)
			(layer "B.CrtYd")
		)
		(fp_line
			(start -4.2 -13.6)
			(end -5.7 -13.6)
			(stroke
				(width 0.05)
				(type solid)
			)
			(layer "B.CrtYd")
		)
		(fp_line
			(start 4.1 -13.6)
			(end 4.1 -12.9)
			(stroke
				(width 0.05)
				(type solid)
			)
			(layer "B.CrtYd")
		)
		(fp_line
			(start 4.1 -13.6)
			(end 5.6 -13.6)
			(stroke
				(width 0.05)
				(type solid)
			)
			(layer "B.CrtYd")
		)
		(fp_line
			(start 5.6 -13.6)
			(end 5.6 -6.6)
			(stroke
				(width 0.05)
				(type solid)
			)
			(layer "B.CrtYd")
		)
		(fp_line
			(start -7.4 12.9)
			(end 7.3 12.9)
			(stroke
				(width 0.05)
				(type solid)
			)
			(layer "F.CrtYd")
		)
		(fp_line
			(start -8.2 -4.6)
			(end -7.4 -4.6)
			(stroke
				(width 0.05)
				(type solid)
			)
			(layer "F.CrtYd")
		)
		(fp_line
			(start -7.4 -4.6)
			(end -7.4 12.9)
			(stroke
				(width 0.05)
				(type solid)
			)
			(layer "F.CrtYd")
		)
		(fp_line
			(start 7.3 -4.6)
			(end 7.3 12.9)
			(stroke
				(width 0.05)
				(type solid)
			)
			(layer "F.CrtYd")
		)
		(fp_line
			(start 8.1 -4.6)
			(end 7.3 -4.6)
			(stroke
				(width 0.05)
				(type solid)
			)
			(layer "F.CrtYd")
		)
		(fp_line
			(start -8.2 -5.5)
			(end -8.2 -4.6)
			(stroke
				(width 0.05)
				(type solid)
			)
			(layer "F.CrtYd")
		)
		(fp_line
			(start -6.6 -5.5)
			(end -8.2 -5.5)
			(stroke
				(width 0.05)
				(type solid)
			)
			(layer "F.CrtYd")
		)
		(fp_line
			(start 6.5 -5.5)
			(end 8.1 -5.5)
			(stroke
				(width 0.05)
				(type solid)
			)
			(layer "F.CrtYd")
		)
		(fp_line
			(start 8.1 -5.5)
			(end 8.1 -4.6)
			(stroke
				(width 0.05)
				(type solid)
			)
			(layer "F.CrtYd")
		)
		(fp_line
			(start -6.6 -6.6)
			(end -6.6 -5.5)
			(stroke
				(width 0.05)
				(type solid)
			)
			(layer "F.CrtYd")
		)
		(fp_line
			(start -5.7 -6.6)
			(end -6.6 -6.6)
			(stroke
				(width 0.05)
				(type solid)
			)
			(layer "F.CrtYd")
		)
		(fp_line
			(start 5.6 -6.6)
			(end 6.5 -6.6)
			(stroke
				(width 0.05)
				(type solid)
			)
			(layer "F.CrtYd")
		)
		(fp_line
			(start 6.5 -6.6)
			(end 6.5 -5.5)
			(stroke
				(width 0.05)
				(type solid)
			)
			(layer "F.CrtYd")
		)
		(fp_line
			(start -4.2 -12.9)
			(end 4.1 -12.9)
			(stroke
				(width 0.05)
				(type solid)
			)
			(layer "F.CrtYd")
		)
		(fp_line
			(start -5.7 -13.6)
			(end -5.7 -6.6)
			(stroke
				(width 0.05)
				(type solid)
			)
			(layer "F.CrtYd")
		)
		(fp_line
			(start -4.2 -13.6)
			(end -4.2 -12.9)
			(stroke
				(width 0.05)
				(type solid)
			)
			(layer "F.CrtYd")
		)
		(fp_line
			(start -4.2 -13.6)
			(end -5.7 -13.6)
			(stroke
				(width 0.05)
				(type solid)
			)
			(layer "F.CrtYd")
		)
		(fp_line
			(start 4.1 -13.6)
			(end 4.1 -12.9)
			(stroke
				(width 0.05)
				(type solid)
			)
			(layer "F.CrtYd")
		)
		(fp_line
			(start 4.1 -13.6)
			(end 5.6 -13.6)
			(stroke
				(width 0.05)
				(type solid)
			)
			(layer "F.CrtYd")
		)
		(fp_line
			(start 5.6 -13.6)
			(end 5.6 -6.6)
			(stroke
				(width 0.05)
				(type solid)
			)
			(layer "F.CrtYd")
		)
		(pad "1" smd rect
			(at 0 -7.872 270)
			(size 1.1 1.75)
			(layers "F.Cu" "F.Mask" "F.Paste")
			(net 253 "/SDI/SDI_IN")
			(pinfunction "1")
			(pintype "passive")
		)
		(pad "2" smd rect
			(at -4.851 -10.221 270)
			(size 1.1 6.45)
			(layers "F.Cu" "F.Mask" "F.Paste")
			(net 1 "GND")
			(pinfunction "2")
			(pintype "passive")
		)
		(pad "2" smd rect
			(at 4.849 -10.221 270)
			(size 1.1 6.45)
			(layers "F.Cu" "F.Mask" "F.Paste")
			(net 1 "GND")
			(pinfunction "2")
			(pintype "passive")
		)
	)
	(footprint "antmicro-footprints:TP_SMD_0.75mm"
		(layer "F.Cu")
		(at 120.53 113.0992 180)
		(property "Reference" "TP19"
			(at 2.75 -0.3408 0)
			(layer "F.SilkS")
			(effects
				(font
					(size 0.65 0.65)
					(thickness 0.15)
				)
				(justify right bottom)
			)
		)
		(property "Value" "TP_0.75mm_SMD"
			(at 0 1.2 0)
			(layer "F.Fab")
			(hide yes)
			(effects
				(font
					(size 0.7 0.7)
					(thickness 0.15)
				)
				(justify right bottom)
			)
		)
		(property "Description" "SMT test point"
			(at 0 0 180)
			(layer "F.Fab")
			(hide yes)
			(effects
				(font
					(size 1.27 1.27)
					(thickness 0.15)
				)
			)
		)
		(property "Author" "Antmicro"
			(at 241.06 226.1984 0)
			(layer "F.Fab")
			(hide yes)
			(effects
				(font
					(size 1 1)
					(thickness 0.15)
				)
			)
		)
		(property "License" "Apache-2.0"
			(at 241.06 226.1984 0)
			(layer "F.Fab")
			(hide yes)
			(effects
				(font
					(size 1 1)
					(thickness 0.15)
				)
			)
		)
		(property "MPN" ""
			(at 241.06 226.1984 0)
			(layer "F.Fab")
			(hide yes)
			(effects
				(font
					(size 1 1)
					(thickness 0.15)
				)
			)
		)
		(property "Manufacturer" ""
			(at 241.06 226.1984 0)
			(layer "F.Fab")
			(hide yes)
			(effects
				(font
					(size 1 1)
					(thickness 0.15)
				)
			)
		)
		(sheetname "/FPGA/")
		(sheetfile "fpga.kicad_sch")
		(attr exclude_from_pos_files)
		(fp_circle
			(center 0 0)
			(end 0.475 0)
			(stroke
				(width 0.05)
				(type default)
			)
			(fill no)
			(layer "F.CrtYd")
		)
		(fp_text user "License: Apache-2.0"
			(at -0.4 5.101 180)
			(layer "F.Fab")
			(effects
				(font
					(size 0.7 0.7)
					(thickness 0.15)
				)
				(justify left bottom)
			)
		)
		(fp_text user "Author: Antmicro"
			(at -0.4 3.901 180)
			(layer "F.Fab")
			(effects
				(font
					(size 0.7 0.7)
					(thickness 0.15)
				)
				(justify left bottom)
			)
		)
		(fp_text user "${REFERENCE}"
			(at -0.4 2.7 180)
			(layer "F.Fab")
			(effects
				(font
					(size 0.7 0.7)
					(thickness 0.15)
				)
				(justify left bottom)
			)
		)
		(pad "1" smd circle
			(at 0 0 180)
			(size 0.75 0.75)
			(layers "F.Cu" "F.Mask")
			(net 40 "/FPGA/DONE")
			(pinfunction "1")
			(pintype "passive")
		)
	)
)
